# S9S_MB_2U (Grand Teton) — schematic netlist excerpt (pin names and nets, part order shuffled) for the footprints in the layout excerpt that follows; sources: Cadence DE-HDL packaged netlist, KiCad conversion of 03242023_DA0F0TMBIJ0_F0T_Motherboard_J_brd_V01_OCP.brd

R275  Q_RES  240 1% CHIP  pkg 0402LF  page 119 : A = PVNN_TERM_CPU0 ; B = PU_CPU0_TXT_AGENT
R2495  Q_RES  1K 1% CHIP  pkg 0402LF  page 115 : A = PWRGD_FAIL_CPU1_CD ; B = PWRGD_FAIL_CPU1_CD_R1
C397  Q_CAP  47UF 4V 20% X6S  pkg C0805  page 75 : A = PVCCIN_CPU0 ; B = GND

(kicad_pcb
	(version 20260206)
	(generator "pcbnew")
	(generator_version "10.0")
	(general
		(thickness 1.6)
		(legacy_teardrops no)
	)
	(paper "A4")
	(title_block
		(title "03242023_DA0F0TMBIJ0_F0T_Motherboard_J_brd_V01_OCP.brd")
		(comment 1 "Grand Teton / footprints 4197-4199 of 6105")
	)
	(layers
		(0 "F.Cu" signal "TOP")
		(4 "In1.Cu" signal "GND")
		(6 "In2.Cu" signal "IN1")
		(8 "In3.Cu" signal "GND1")
		(10 "In4.Cu" signal "IN2")
		(12 "In5.Cu" signal "GND2")
		(14 "In6.Cu" signal "IN3")
		(16 "In7.Cu" signal "GND3")
		(18 "In8.Cu" signal "VCC")
		(20 "In9.Cu" signal "VCC1")
		(22 "In10.Cu" signal "GND4")
		(24 "In11.Cu" signal "IN4")
		(26 "In12.Cu" signal "GND5")
		(28 "In13.Cu" signal "IN5")
		(30 "In14.Cu" signal "GND6")
		(32 "In15.Cu" signal "IN6")
		(34 "In16.Cu" signal "GND7")
		(2 "B.Cu" signal "BOTTOM")
		(9 "F.Adhes" user "F.Adhesive")
		(11 "B.Adhes" user "B.Adhesive")
		(13 "F.Paste" user "Package Geometry/Pastemask Top")
		(15 "B.Paste" user "Package Geometry/Pastemask Bottom")
		(5 "F.SilkS" user "Ref Des/Silkscreen Top")
		(7 "B.SilkS" user "Ref Des/Silkscreen Bottom")
		(1 "F.Mask" user "Board Geometry/Soldermask Top")
		(3 "B.Mask" user "Board Geometry/Soldermask Bottom")
		(17 "Dwgs.User" user "User.Drawings")
		(19 "Cmts.User" user "User.Comments")
		(21 "Eco1.User" user "User.Eco1")
		(23 "Eco2.User" user "User.Eco2")
		(25 "Edge.Cuts" user "Board Geometry/Outline")
		(27 "Margin" user)
		(31 "F.CrtYd" user "Package Geometry/Place Bound Top")
		(29 "B.CrtYd" user "Package Geometry/Place Bound Bottom")
		(35 "F.Fab" user "Ref Des/Assembly Top")
		(33 "B.Fab" user "Ref Des/Assembly Bottom")
	)
	(footprint ""
		(layer "B.Cu")
		(at 324.423278 -186.68619 -90)
		(property "Reference" "R275"
			(at 0 0 90)
			(layer "B.SilkS")
			(hide yes)
			(effects
				(font
					(size 1.27 1.27)
				)
				(justify mirror)
			)
		)
		(property "Value" ""
			(at 0 0 90)
			(layer "B.Fab")
			(effects
				(font
					(size 1.27 1.27)
				)
				(justify mirror)
			)
		)
		(duplicate_pad_numbers_are_jumpers no)
		(fp_line
			(start -0.7874 0.4064)
			(end 0.7874 0.4064)
			(stroke
				(width 0.1524)
				(type default)
			)
			(layer "B.SilkS")
		)
		(fp_line
			(start 0.7874 0.4064)
			(end 0.7874 -0.4064)
			(stroke
				(width 0.1524)
				(type default)
			)
			(layer "B.SilkS")
		)
		(fp_line
			(start -0.7874 -0.4064)
			(end -0.7874 0.4064)
			(stroke
				(width 0.1524)
				(type default)
			)
			(layer "B.SilkS")
		)
		(fp_line
			(start 0.7874 -0.4064)
			(end -0.7874 -0.4064)
			(stroke
				(width 0.1524)
				(type default)
			)
			(layer "B.SilkS")
		)
		(fp_line
			(start -0.67945 0.3048)
			(end -0.120396 0.3048)
			(stroke
				(width 0.1)
				(type default)
			)
			(layer "B.Fab")
		)
		(fp_line
			(start -0.120396 0.3048)
			(end -0.120396 0.2794)
			(stroke
				(width 0.1)
				(type default)
			)
			(layer "B.Fab")
		)
		(fp_line
			(start 0.12065 0.3048)
			(end 0.67945 0.3048)
			(stroke
				(width 0.1)
				(type default)
			)
			(layer "B.Fab")
		)
		(fp_line
			(start 0.67945 0.3048)
			(end 0.67945 -0.305054)
			(stroke
				(width 0.1)
				(type default)
			)
			(layer "B.Fab")
		)
		(fp_line
			(start -0.120396 0.2794)
			(end 0.12065 0.2794)
			(stroke
				(width 0.1)
				(type default)
			)
			(layer "B.Fab")
		)
		(fp_line
			(start 0.12065 0.2794)
			(end 0.12065 0.3048)
			(stroke
				(width 0.1)
				(type default)
			)
			(layer "B.Fab")
		)
		(fp_line
			(start -0.12065 -0.2794)
			(end -0.12065 -0.3048)
			(stroke
				(width 0.1)
				(type default)
			)
			(layer "B.Fab")
		)
		(fp_line
			(start 0.12065 -0.2794)
			(end -0.12065 -0.2794)
			(stroke
				(width 0.1)
				(type default)
			)
			(layer "B.Fab")
		)
		(fp_line
			(start -0.67945 -0.3048)
			(end -0.67945 0.3048)
			(stroke
				(width 0.1)
				(type default)
			)
			(layer "B.Fab")
		)
		(fp_line
			(start -0.12065 -0.3048)
			(end -0.67945 -0.3048)
			(stroke
				(width 0.1)
				(type default)
			)
			(layer "B.Fab")
		)
		(fp_line
			(start 0.12065 -0.305054)
			(end 0.12065 -0.2794)
			(stroke
				(width 0.1)
				(type default)
			)
			(layer "B.Fab")
		)
		(fp_line
			(start 0.67945 -0.305054)
			(end 0.12065 -0.305054)
			(stroke
				(width 0.1)
				(type default)
			)
			(layer "B.Fab")
		)
		(pad "1" smd circle
			(at 0.40005 0 90)
			(size 0 0)
			(layers "B.Cu" "B.Mask" "B.Paste")
			(net "PVNN_TERM_CPU0")
		)
		(pad "2" smd circle
			(at -0.40005 0 90)
			(size 0 0)
			(layers "B.Cu" "B.Mask" "B.Paste")
			(net "PU_CPU0_TXT_AGENT")
		)
	)
	(footprint ""
		(layer "B.Cu")
		(at 351.841308 -244.820186 -90)
		(property "Reference" "C397"
			(at 0 0 90)
			(layer "B.SilkS")
			(hide yes)
			(effects
				(font
					(size 1.27 1.27)
				)
				(justify mirror)
			)
		)
		(property "Value" ""
			(at 0 0 90)
			(layer "B.Fab")
			(effects
				(font
					(size 1.27 1.27)
				)
				(justify mirror)
			)
		)
		(duplicate_pad_numbers_are_jumpers no)
		(fp_line
			(start -1.524 0.762)
			(end 1.524 0.762)
			(stroke
				(width 0.1524)
				(type default)
			)
			(layer "B.SilkS")
		)
		(fp_line
			(start 1.524 0.762)
			(end 1.524 -0.762)
			(stroke
				(width 0.1524)
				(type default)
			)
			(layer "B.SilkS")
		)
		(fp_line
			(start -1.524 -0.762)
			(end -1.524 0.762)
			(stroke
				(width 0.1524)
				(type default)
			)
			(layer "B.SilkS")
		)
		(fp_line
			(start 1.524 -0.762)
			(end -1.524 -0.762)
			(stroke
				(width 0.1524)
				(type default)
			)
			(layer "B.SilkS")
		)
		(fp_line
			(start -1.1049 0.724916)
			(end -1.1049 -0.724916)
			(stroke
				(width 0.1)
				(type default)
			)
			(layer "B.Fab")
		)
		(fp_line
			(start 1.1049 0.724916)
			(end -1.1049 0.724916)
			(stroke
				(width 0.1)
				(type default)
			)
			(layer "B.Fab")
		)
		(fp_line
			(start -1.1049 -0.724916)
			(end 1.1049 -0.724916)
			(stroke
				(width 0.1)
				(type default)
			)
			(layer "B.Fab")
		)
		(fp_line
			(start 1.1049 -0.724916)
			(end 1.1049 0.724916)
			(stroke
				(width 0.1)
				(type default)
			)
			(layer "B.Fab")
		)
		(pad "1" smd rect
			(at 0.889 0 270)
			(size 1.016 1.27)
			(layers "B.Cu" "B.Mask" "B.Paste")
			(net "PVCCIN_CPU0")
		)
		(pad "2" smd rect
			(at -0.889 0 270)
			(size 1.016 1.27)
			(layers "B.Cu" "B.Mask" "B.Paste")
			(net "GND")
		)
	)
	(footprint ""
		(layer "B.Cu")
		(at 36.12896 -319.519808 180)
		(property "Reference" "R2495"
			(at 0 0 0)
			(layer "B.SilkS")
			(hide yes)
			(effects
				(font
					(size 1.27 1.27)
				)
				(justify mirror)
			)
		)
		(property "Value" ""
			(at 0 0 0)
			(layer "B.Fab")
			(effects
				(font
					(size 1.27 1.27)
				)
				(justify mirror)
			)
		)
		(duplicate_pad_numbers_are_jumpers no)
		(fp_line
			(start 0.7874 0.4064)
			(end 0.7874 -0.4064)
			(stroke
				(width 0.1524)
				(type default)
			)
			(layer "B.SilkS")
		)
		(fp_line
			(start 0.7874 -0.4064)
			(end -0.7874 -0.4064)
			(stroke
				(width 0.1524)
				(type default)
			)
			(layer "B.SilkS")
		)
		(fp_line
			(start -0.7874 0.4064)
			(end 0.7874 0.4064)
			(stroke
				(width 0.1524)
				(type default)
			)
			(layer "B.SilkS")
		)
		(fp_line
			(start -0.7874 -0.4064)
			(end -0.7874 0.4064)
			(stroke
				(width 0.1524)
				(type default)
			)
			(layer "B.SilkS")
		)
		(fp_line
			(start 0.67945 0.3048)
			(end 0.67945 -0.305054)
			(stroke
				(width 0.1)
				(type default)
			)
			(layer "B.Fab")
		)
		(fp_line
			(start 0.67945 -0.305054)
			(end 0.12065 -0.305054)
			(stroke
				(width 0.1)
				(type default)
			)
			(layer "B.Fab")
		)
		(fp_line
			(start 0.12065 0.3048)
			(end 0.67945 0.3048)
			(stroke
				(width 0.1)
				(type default)
			)
			(layer "B.Fab")
		)
		(fp_line
			(start 0.12065 0.2794)
			(end 0.12065 0.3048)
			(stroke
				(width 0.1)
				(type default)
			)
			(layer "B.Fab")
		)
		(fp_line
			(start 0.12065 -0.2794)
			(end -0.12065 -0.2794)
			(stroke
				(width 0.1)
				(type default)
			)
			(layer "B.Fab")
		)
		(fp_line
			(start 0.12065 -0.305054)
			(end 0.12065 -0.2794)
			(stroke
				(width 0.1)
				(type default)
			)
			(layer "B.Fab")
		)
		(fp_line
			(start -0.120396 0.3048)
			(end -0.120396 0.2794)
			(stroke
				(width 0.1)
				(type default)
			)
			(layer "B.Fab")
		)
		(fp_line
			(start -0.120396 0.2794)
			(end 0.12065 0.2794)
			(stroke
				(width 0.1)
				(type default)
			)
			(layer "B.Fab")
		)
		(fp_line
			(start -0.12065 -0.2794)
			(end -0.12065 -0.3048)
			(stroke
				(width 0.1)
				(type default)
			)
			(layer "B.Fab")
		)
		(fp_line
			(start -0.12065 -0.3048)
			(end -0.67945 -0.3048)
			(stroke
				(width 0.1)
				(type default)
			)
			(layer "B.Fab")
		)
		(fp_line
			(start -0.67945 0.3048)
			(end -0.120396 0.3048)
			(stroke
				(width 0.1)
				(type default)
			)
			(layer "B.Fab")
		)
		(fp_line
			(start -0.67945 -0.3048)
			(end -0.67945 0.3048)
			(stroke
				(width 0.1)
				(type default)
			)
			(layer "B.Fab")
		)
		(pad "1" smd circle
			(at 0.40005 0)
			(size 0 0)
			(layers "B.Cu" "B.Mask" "B.Paste")
			(net "PWRGD_FAIL_CPU1_CD")
		)
		(pad "2" smd circle
			(at -0.40005 0)
			(size 0 0)
			(layers "B.Cu" "B.Mask" "B.Paste")
			(net "PWRGD_FAIL_CPU1_CD_R1")
		)
	)
)
